# T6G (Grand Teton) — schematic netlist excerpt (pin names and nets, part order shuffled) for the footprints in the layout excerpt that follows; sources: Cadence DE-HDL packaged netlist, KiCad conversion of 04192023_DAF0TMB3IC0_F0TG_MB_C_brd_V02_OCP.brd

C2139  Q_CAP  22UF 4V 20% X6S  pkg C0402  page 68 : A = PVDDCR_SOC_P0 ; B = GND
R1088  Q_RES  0 5% CHIP  pkg 0201LF  page 309 : A = RST_RT_CPU0_P3_PERST_N ; B = RST_RT_CPU0_P3_PERST_R_N
PC6008  Q_CAP  1UF 25V 10% X6S  pkg C0402  page 269 : A = P1V8_AUX_VCC ; B = GND

(kicad_pcb
	(version 20260206)
	(generator "pcbnew")
	(generator_version "10.0")
	(general
		(thickness 1.6)
		(legacy_teardrops no)
	)
	(paper "A4")
	(title_block
		(title "04192023_DAF0TMB3IC0_F0TG_MB_C_brd_V02_OCP.brd")
		(comment 1 "Grand Teton / footprints 3472-3474 of 8354")
	)
	(layers
		(0 "F.Cu" signal "TOP")
		(4 "In1.Cu" signal "GND")
		(6 "In2.Cu" signal "IN1")
		(8 "In3.Cu" signal "GND1")
		(10 "In4.Cu" signal "IN2")
		(12 "In5.Cu" signal "GND2")
		(14 "In6.Cu" signal "IN3")
		(16 "In7.Cu" signal "GND3")
		(18 "In8.Cu" signal "VCC")
		(20 "In9.Cu" signal "VCC1")
		(22 "In10.Cu" signal "GND4")
		(24 "In11.Cu" signal "IN4")
		(26 "In12.Cu" signal "GND5")
		(28 "In13.Cu" signal "IN5")
		(30 "In14.Cu" signal "GND6")
		(32 "In15.Cu" signal "IN6")
		(34 "In16.Cu" signal "GND7")
		(2 "B.Cu" signal "BOTTOM")
		(9 "F.Adhes" user "F.Adhesive")
		(11 "B.Adhes" user "B.Adhesive")
		(13 "F.Paste" user "Package Geometry/Pastemask Top")
		(15 "B.Paste" user "Package Geometry/Pastemask Bottom")
		(5 "F.SilkS" user "Ref Des/Silkscreen Top")
		(7 "B.SilkS" user "Ref Des/Silkscreen Bottom")
		(1 "F.Mask" user "Board Geometry/Soldermask Top")
		(3 "B.Mask" user "Board Geometry/Soldermask Bottom")
		(17 "Dwgs.User" user "User.Drawings")
		(19 "Cmts.User" user "User.Comments")
		(21 "Eco1.User" user "User.Eco1")
		(23 "Eco2.User" user "User.Eco2")
		(25 "Edge.Cuts" user "Board Geometry/Outline")
		(27 "Margin" user)
		(31 "F.CrtYd" user "Package Geometry/Place Bound Top")
		(29 "B.CrtYd" user "Package Geometry/Place Bound Bottom")
		(35 "F.Fab" user "Ref Des/Assembly Top")
		(33 "B.Fab" user "Ref Des/Assembly Bottom")
	)
	(footprint ""
		(layer "F.Cu")
		(at 365.835692 -260.305042 180)
		(property "Reference" "C2139"
			(at 0 0 180)
			(layer "F.SilkS")
			(hide yes)
			(effects
				(font
					(size 1.27 1.27)
				)
			)
		)
		(property "Value" ""
			(at 0 0 180)
			(layer "F.Fab")
			(effects
				(font
					(size 1.27 1.27)
				)
			)
		)
		(duplicate_pad_numbers_are_jumpers no)
		(fp_line
			(start 0.7874 0.4064)
			(end -0.7874 0.4064)
			(stroke
				(width 0.1524)
				(type default)
			)
			(layer "F.SilkS")
		)
		(fp_line
			(start 0.7874 -0.4064)
			(end 0.7874 0.4064)
			(stroke
				(width 0.1524)
				(type default)
			)
			(layer "F.SilkS")
		)
		(fp_line
			(start -0.7874 0.4064)
			(end -0.7874 -0.4064)
			(stroke
				(width 0.1524)
				(type default)
			)
			(layer "F.SilkS")
		)
		(fp_line
			(start -0.7874 -0.4064)
			(end 0.7874 -0.4064)
			(stroke
				(width 0.1524)
				(type default)
			)
			(layer "F.SilkS")
		)
		(fp_line
			(start 0.67945 0.3048)
			(end 0.120396 0.3048)
			(stroke
				(width 0.1)
				(type default)
			)
			(layer "F.Fab")
		)
		(fp_line
			(start 0.67945 -0.3048)
			(end 0.67945 0.3048)
			(stroke
				(width 0.1)
				(type default)
			)
			(layer "F.Fab")
		)
		(fp_line
			(start 0.12065 -0.2794)
			(end 0.12065 -0.3048)
			(stroke
				(width 0.1)
				(type default)
			)
			(layer "F.Fab")
		)
		(fp_line
			(start 0.12065 -0.3048)
			(end 0.67945 -0.3048)
			(stroke
				(width 0.1)
				(type default)
			)
			(layer "F.Fab")
		)
		(fp_line
			(start 0.120396 0.3048)
			(end 0.120396 0.2794)
			(stroke
				(width 0.1)
				(type default)
			)
			(layer "F.Fab")
		)
		(fp_line
			(start 0.120396 0.2794)
			(end -0.12065 0.2794)
			(stroke
				(width 0.1)
				(type default)
			)
			(layer "F.Fab")
		)
		(fp_line
			(start -0.12065 0.3048)
			(end -0.67945 0.3048)
			(stroke
				(width 0.1)
				(type default)
			)
			(layer "F.Fab")
		)
		(fp_line
			(start -0.12065 0.2794)
			(end -0.12065 0.3048)
			(stroke
				(width 0.1)
				(type default)
			)
			(layer "F.Fab")
		)
		(fp_line
			(start -0.12065 -0.2794)
			(end 0.12065 -0.2794)
			(stroke
				(width 0.1)
				(type default)
			)
			(layer "F.Fab")
		)
		(fp_line
			(start -0.12065 -0.305054)
			(end -0.12065 -0.2794)
			(stroke
				(width 0.1)
				(type default)
			)
			(layer "F.Fab")
		)
		(fp_line
			(start -0.67945 0.3048)
			(end -0.67945 -0.305054)
			(stroke
				(width 0.1)
				(type default)
			)
			(layer "F.Fab")
		)
		(fp_line
			(start -0.67945 -0.305054)
			(end -0.12065 -0.305054)
			(stroke
				(width 0.1)
				(type default)
			)
			(layer "F.Fab")
		)
		(pad "1" smd circle
			(at -0.40005 0 180)
			(size 0 0)
			(layers "F.Cu" "F.Mask" "F.Paste")
			(net "PVDDCR_SOC_P0")
		)
		(pad "2" smd circle
			(at 0.40005 0 180)
			(size 0 0)
			(layers "F.Cu" "F.Mask" "F.Paste")
			(net "GND")
		)
	)
	(footprint ""
		(layer "F.Cu")
		(at 143.46047 -80.977486 180)
		(property "Reference" "PC6008"
			(at 0 0 180)
			(layer "F.SilkS")
			(hide yes)
			(effects
				(font
					(size 1.27 1.27)
				)
			)
		)
		(property "Value" ""
			(at 0 0 180)
			(layer "F.Fab")
			(effects
				(font
					(size 1.27 1.27)
				)
			)
		)
		(duplicate_pad_numbers_are_jumpers no)
		(fp_line
			(start 0.7874 0.4064)
			(end -0.7874 0.4064)
			(stroke
				(width 0.1524)
				(type default)
			)
			(layer "F.SilkS")
		)
		(fp_line
			(start 0.7874 -0.4064)
			(end 0.7874 0.4064)
			(stroke
				(width 0.1524)
				(type default)
			)
			(layer "F.SilkS")
		)
		(fp_line
			(start -0.7874 0.4064)
			(end -0.7874 -0.4064)
			(stroke
				(width 0.1524)
				(type default)
			)
			(layer "F.SilkS")
		)
		(fp_line
			(start -0.7874 -0.4064)
			(end 0.7874 -0.4064)
			(stroke
				(width 0.1524)
				(type default)
			)
			(layer "F.SilkS")
		)
		(fp_line
			(start 0.67945 0.3048)
			(end 0.120396 0.3048)
			(stroke
				(width 0.1)
				(type default)
			)
			(layer "F.Fab")
		)
		(fp_line
			(start 0.67945 -0.3048)
			(end 0.67945 0.3048)
			(stroke
				(width 0.1)
				(type default)
			)
			(layer "F.Fab")
		)
		(fp_line
			(start 0.12065 -0.2794)
			(end 0.12065 -0.3048)
			(stroke
				(width 0.1)
				(type default)
			)
			(layer "F.Fab")
		)
		(fp_line
			(start 0.12065 -0.3048)
			(end 0.67945 -0.3048)
			(stroke
				(width 0.1)
				(type default)
			)
			(layer "F.Fab")
		)
		(fp_line
			(start 0.120396 0.3048)
			(end 0.120396 0.2794)
			(stroke
				(width 0.1)
				(type default)
			)
			(layer "F.Fab")
		)
		(fp_line
			(start 0.120396 0.2794)
			(end -0.12065 0.2794)
			(stroke
				(width 0.1)
				(type default)
			)
			(layer "F.Fab")
		)
		(fp_line
			(start -0.12065 0.3048)
			(end -0.67945 0.3048)
			(stroke
				(width 0.1)
				(type default)
			)
			(layer "F.Fab")
		)
		(fp_line
			(start -0.12065 0.2794)
			(end -0.12065 0.3048)
			(stroke
				(width 0.1)
				(type default)
			)
			(layer "F.Fab")
		)
		(fp_line
			(start -0.12065 -0.2794)
			(end 0.12065 -0.2794)
			(stroke
				(width 0.1)
				(type default)
			)
			(layer "F.Fab")
		)
		(fp_line
			(start -0.12065 -0.305054)
			(end -0.12065 -0.2794)
			(stroke
				(width 0.1)
				(type default)
			)
			(layer "F.Fab")
		)
		(fp_line
			(start -0.67945 0.3048)
			(end -0.67945 -0.305054)
			(stroke
				(width 0.1)
				(type default)
			)
			(layer "F.Fab")
		)
		(fp_line
			(start -0.67945 -0.305054)
			(end -0.12065 -0.305054)
			(stroke
				(width 0.1)
				(type default)
			)
			(layer "F.Fab")
		)
		(pad "1" smd circle
			(at -0.40005 0 180)
			(size 0 0)
			(layers "F.Cu" "F.Mask" "F.Paste")
			(net "P1V8_AUX_VCC")
		)
		(pad "2" smd circle
			(at 0.40005 0 180)
			(size 0 0)
			(layers "F.Cu" "F.Mask" "F.Paste")
			(net "GND")
		)
	)
	(footprint ""
		(layer "F.Cu")
		(at 391.268458 -404.0124 -90)
		(property "Reference" "R1088"
			(at 0 0 270)
			(layer "F.SilkS")
			(hide yes)
			(effects
				(font
					(size 1.27 1.27)
				)
			)
		)
		(property "Value" ""
			(at 0 0 270)
			(layer "F.Fab")
			(effects
				(font
					(size 1.27 1.27)
				)
			)
		)
		(duplicate_pad_numbers_are_jumpers no)
		(fp_line
			(start -0.32512 0.175006)
			(end -0.32512 -0.175006)
			(stroke
				(width 0.1)
				(type default)
			)
			(layer "F.Fab")
		)
		(fp_line
			(start 0.32512 0.175006)
			(end -0.32512 0.175006)
			(stroke
				(width 0.1)
				(type default)
			)
			(layer "F.Fab")
		)
		(fp_line
			(start -0.32512 -0.175006)
			(end 0.32512 -0.175006)
			(stroke
				(width 0.1)
				(type default)
			)
			(layer "F.Fab")
		)
		(fp_line
			(start 0.32512 -0.175006)
			(end 0.32512 0.175006)
			(stroke
				(width 0.1)
				(type default)
			)
			(layer "F.Fab")
		)
		(pad "1" smd rect
			(at -0.2667 0 270)
			(size 0.3048 0.381)
			(layers "F.Cu" "F.Mask" "F.Paste")
			(net "RST_RT_CPU0_P3_PERST_N")
		)
		(pad "2" smd rect
			(at 0.2667 0 90)
			(size 0.3048 0.381)
			(layers "F.Cu" "F.Mask" "F.Paste")
			(net "RST_RT_CPU0_P3_PERST_R_N")
		)
	)
)
